# S9S_MB_2U (Grand Teton) — schematic netlist excerpt (pin names and nets, part order shuffled) for the footprints in the layout excerpt that follows; sources: Cadence DE-HDL packaged netlist, KiCad conversion of 03242023_DA0F0TMBIJ0_F0T_Motherboard_J_brd_V01_OCP.brd

R130  Q_RES  0 5% CHIP  pkg 0402LF  page 125 : A = PWRGD_CPU1_LVC1_R ; B = PWRGD_CPU1_BUF_R
PR4004  Q_RES  17.8K 1% EMPTY  pkg 0402LF  page 242 : A = P12V_SCM_CB ; B = GND

(kicad_pcb
	(version 20260206)
	(generator "pcbnew")
	(generator_version "10.0")
	(general
		(thickness 1.6)
		(legacy_teardrops no)
	)
	(paper "A4")
	(title_block
		(title "03242023_DA0F0TMBIJ0_F0T_Motherboard_J_brd_V01_OCP.brd")
		(comment 1 "Grand Teton / footprints 1917-1918 of 6105")
	)
	(layers
		(0 "F.Cu" signal "TOP")
		(4 "In1.Cu" signal "GND")
		(6 "In2.Cu" signal "IN1")
		(8 "In3.Cu" signal "GND1")
		(10 "In4.Cu" signal "IN2")
		(12 "In5.Cu" signal "GND2")
		(14 "In6.Cu" signal "IN3")
		(16 "In7.Cu" signal "GND3")
		(18 "In8.Cu" signal "VCC")
		(20 "In9.Cu" signal "VCC1")
		(22 "In10.Cu" signal "GND4")
		(24 "In11.Cu" signal "IN4")
		(26 "In12.Cu" signal "GND5")
		(28 "In13.Cu" signal "IN5")
		(30 "In14.Cu" signal "GND6")
		(32 "In15.Cu" signal "IN6")
		(34 "In16.Cu" signal "GND7")
		(2 "B.Cu" signal "BOTTOM")
		(9 "F.Adhes" user "F.Adhesive")
		(11 "B.Adhes" user "B.Adhesive")
		(13 "F.Paste" user "Package Geometry/Pastemask Top")
		(15 "B.Paste" user "Package Geometry/Pastemask Bottom")
		(5 "F.SilkS" user "Ref Des/Silkscreen Top")
		(7 "B.SilkS" user "Ref Des/Silkscreen Bottom")
		(1 "F.Mask" user "Board Geometry/Soldermask Top")
		(3 "B.Mask" user "Board Geometry/Soldermask Bottom")
		(17 "Dwgs.User" user "User.Drawings")
		(19 "Cmts.User" user "User.Comments")
		(21 "Eco1.User" user "User.Eco1")
		(23 "Eco2.User" user "User.Eco2")
		(25 "Edge.Cuts" user "Board Geometry/Outline")
		(27 "Margin" user)
		(31 "F.CrtYd" user "Package Geometry/Place Bound Top")
		(29 "B.CrtYd" user "Package Geometry/Place Bound Bottom")
		(35 "F.Fab" user "Ref Des/Assembly Top")
		(33 "B.Fab" user "Ref Des/Assembly Bottom")
	)
	(footprint ""
		(layer "F.Cu")
		(at 184.96788 -99.659948 -90)
		(property "Reference" "R130"
			(at 0 0 270)
			(layer "F.SilkS")
			(hide yes)
			(effects
				(font
					(size 1.27 1.27)
				)
			)
		)
		(property "Value" ""
			(at 0 0 270)
			(layer "F.Fab")
			(effects
				(font
					(size 1.27 1.27)
				)
			)
		)
		(duplicate_pad_numbers_are_jumpers no)
		(fp_line
			(start -0.7874 0.4064)
			(end -0.7874 -0.4064)
			(stroke
				(width 0.1524)
				(type default)
			)
			(layer "F.SilkS")
		)
		(fp_line
			(start 0.7874 0.4064)
			(end -0.7874 0.4064)
			(stroke
				(width 0.1524)
				(type default)
			)
			(layer "F.SilkS")
		)
		(fp_line
			(start -0.7874 -0.4064)
			(end 0.7874 -0.4064)
			(stroke
				(width 0.1524)
				(type default)
			)
			(layer "F.SilkS")
		)
		(fp_line
			(start 0.7874 -0.4064)
			(end 0.7874 0.4064)
			(stroke
				(width 0.1524)
				(type default)
			)
			(layer "F.SilkS")
		)
		(fp_line
			(start -0.67945 0.3048)
			(end -0.67945 -0.305054)
			(stroke
				(width 0.1)
				(type default)
			)
			(layer "F.Fab")
		)
		(fp_line
			(start -0.12065 0.3048)
			(end -0.67945 0.3048)
			(stroke
				(width 0.1)
				(type default)
			)
			(layer "F.Fab")
		)
		(fp_line
			(start 0.120396 0.3048)
			(end 0.120396 0.2794)
			(stroke
				(width 0.1)
				(type default)
			)
			(layer "F.Fab")
		)
		(fp_line
			(start 0.67945 0.3048)
			(end 0.120396 0.3048)
			(stroke
				(width 0.1)
				(type default)
			)
			(layer "F.Fab")
		)
		(fp_line
			(start -0.12065 0.2794)
			(end -0.12065 0.3048)
			(stroke
				(width 0.1)
				(type default)
			)
			(layer "F.Fab")
		)
		(fp_line
			(start 0.120396 0.2794)
			(end -0.12065 0.2794)
			(stroke
				(width 0.1)
				(type default)
			)
			(layer "F.Fab")
		)
		(fp_line
			(start -0.12065 -0.2794)
			(end 0.12065 -0.2794)
			(stroke
				(width 0.1)
				(type default)
			)
			(layer "F.Fab")
		)
		(fp_line
			(start 0.12065 -0.2794)
			(end 0.12065 -0.3048)
			(stroke
				(width 0.1)
				(type default)
			)
			(layer "F.Fab")
		)
		(fp_line
			(start 0.12065 -0.3048)
			(end 0.67945 -0.3048)
			(stroke
				(width 0.1)
				(type default)
			)
			(layer "F.Fab")
		)
		(fp_line
			(start 0.67945 -0.3048)
			(end 0.67945 0.3048)
			(stroke
				(width 0.1)
				(type default)
			)
			(layer "F.Fab")
		)
		(fp_line
			(start -0.67945 -0.305054)
			(end -0.12065 -0.305054)
			(stroke
				(width 0.1)
				(type default)
			)
			(layer "F.Fab")
		)
		(fp_line
			(start -0.12065 -0.305054)
			(end -0.12065 -0.2794)
			(stroke
				(width 0.1)
				(type default)
			)
			(layer "F.Fab")
		)
		(pad "1" smd circle
			(at -0.40005 0 270)
			(size 0 0)
			(layers "F.Cu" "F.Mask" "F.Paste")
			(net "PWRGD_CPU1_LVC1_R")
		)
		(pad "2" smd circle
			(at 0.40005 0 270)
			(size 0 0)
			(layers "F.Cu" "F.Mask" "F.Paste")
			(net "PWRGD_CPU1_BUF_R")
		)
	)
	(footprint ""
		(layer "F.Cu")
		(at 185.928762 -25.899872 180)
		(property "Reference" "PR4004"
			(at 0 0 180)
			(layer "F.SilkS")
			(hide yes)
			(effects
				(font
					(size 1.27 1.27)
				)
			)
		)
		(property "Value" ""
			(at 0 0 180)
			(layer "F.Fab")
			(effects
				(font
					(size 1.27 1.27)
				)
			)
		)
		(duplicate_pad_numbers_are_jumpers no)
		(fp_line
			(start 0.7874 0.4064)
			(end -0.7874 0.4064)
			(stroke
				(width 0.1524)
				(type default)
			)
			(layer "F.SilkS")
		)
		(fp_line
			(start 0.7874 -0.4064)
			(end 0.7874 0.4064)
			(stroke
				(width 0.1524)
				(type default)
			)
			(layer "F.SilkS")
		)
		(fp_line
			(start -0.7874 0.4064)
			(end -0.7874 -0.4064)
			(stroke
				(width 0.1524)
				(type default)
			)
			(layer "F.SilkS")
		)
		(fp_line
			(start -0.7874 -0.4064)
			(end 0.7874 -0.4064)
			(stroke
				(width 0.1524)
				(type default)
			)
			(layer "F.SilkS")
		)
		(fp_line
			(start 0.67945 0.3048)
			(end 0.120396 0.3048)
			(stroke
				(width 0.1)
				(type default)
			)
			(layer "F.Fab")
		)
		(fp_line
			(start 0.67945 -0.3048)
			(end 0.67945 0.3048)
			(stroke
				(width 0.1)
				(type default)
			)
			(layer "F.Fab")
		)
		(fp_line
			(start 0.12065 -0.2794)
			(end 0.12065 -0.3048)
			(stroke
				(width 0.1)
				(type default)
			)
			(layer "F.Fab")
		)
		(fp_line
			(start 0.12065 -0.3048)
			(end 0.67945 -0.3048)
			(stroke
				(width 0.1)
				(type default)
			)
			(layer "F.Fab")
		)
		(fp_line
			(start 0.120396 0.3048)
			(end 0.120396 0.2794)
			(stroke
				(width 0.1)
				(type default)
			)
			(layer "F.Fab")
		)
		(fp_line
			(start 0.120396 0.2794)
			(end -0.12065 0.2794)
			(stroke
				(width 0.1)
				(type default)
			)
			(layer "F.Fab")
		)
		(fp_line
			(start -0.12065 0.3048)
			(end -0.67945 0.3048)
			(stroke
				(width 0.1)
				(type default)
			)
			(layer "F.Fab")
		)
		(fp_line
			(start -0.12065 0.2794)
			(end -0.12065 0.3048)
			(stroke
				(width 0.1)
				(type default)
			)
			(layer "F.Fab")
		)
		(fp_line
			(start -0.12065 -0.2794)
			(end 0.12065 -0.2794)
			(stroke
				(width 0.1)
				(type default)
			)
			(layer "F.Fab")
		)
		(fp_line
			(start -0.12065 -0.305054)
			(end -0.12065 -0.2794)
			(stroke
				(width 0.1)
				(type default)
			)
			(layer "F.Fab")
		)
		(fp_line
			(start -0.67945 0.3048)
			(end -0.67945 -0.305054)
			(stroke
				(width 0.1)
				(type default)
			)
			(layer "F.Fab")
		)
		(fp_line
			(start -0.67945 -0.305054)
			(end -0.12065 -0.305054)
			(stroke
				(width 0.1)
				(type default)
			)
			(layer "F.Fab")
		)
		(pad "1" smd circle
			(at -0.40005 0 180)
			(size 0 0)
			(layers "F.Cu" "F.Mask" "F.Paste")
			(net "P12V_SCM_CB")
		)
		(pad "2" smd circle
			(at 0.40005 0 180)
			(size 0 0)
			(layers "F.Cu" "F.Mask" "F.Paste")
			(net "GND")
		)
	)
)
